# S9S_MB_2U (Grand Teton) — schematic netlist excerpt (pin names and nets, part order shuffled) for the footprints in the layout excerpt that follows; sources: Cadence DE-HDL packaged netlist, KiCad conversion of 03242023_DA0F0TMBIJ0_F0T_Motherboard_J_brd_V01_OCP.brd

PC1273  Q_CAP  22UF 16V 20% X6S  pkg C0805  page 282 : A = SW_P12V_PVCCINFAON_CPU0_FLT ; B = GND
R148  Q_RES  10K 1% EMPTY  pkg 0402LF  page 197 : A = PECI_BMC_R ; B = GND

(kicad_pcb
	(version 20260206)
	(generator "pcbnew")
	(generator_version "10.0")
	(general
		(thickness 1.6)
		(legacy_teardrops no)
	)
	(paper "A4")
	(title_block
		(title "03242023_DA0F0TMBIJ0_F0T_Motherboard_J_brd_V01_OCP.brd")
		(comment 1 "Grand Teton / footprints 3690-3691 of 6105")
	)
	(layers
		(0 "F.Cu" signal "TOP")
		(4 "In1.Cu" signal "GND")
		(6 "In2.Cu" signal "IN1")
		(8 "In3.Cu" signal "GND1")
		(10 "In4.Cu" signal "IN2")
		(12 "In5.Cu" signal "GND2")
		(14 "In6.Cu" signal "IN3")
		(16 "In7.Cu" signal "GND3")
		(18 "In8.Cu" signal "VCC")
		(20 "In9.Cu" signal "VCC1")
		(22 "In10.Cu" signal "GND4")
		(24 "In11.Cu" signal "IN4")
		(26 "In12.Cu" signal "GND5")
		(28 "In13.Cu" signal "IN5")
		(30 "In14.Cu" signal "GND6")
		(32 "In15.Cu" signal "IN6")
		(34 "In16.Cu" signal "GND7")
		(2 "B.Cu" signal "BOTTOM")
		(9 "F.Adhes" user "F.Adhesive")
		(11 "B.Adhes" user "B.Adhesive")
		(13 "F.Paste" user "Package Geometry/Pastemask Top")
		(15 "B.Paste" user "Package Geometry/Pastemask Bottom")
		(5 "F.SilkS" user "Ref Des/Silkscreen Top")
		(7 "B.SilkS" user "Ref Des/Silkscreen Bottom")
		(1 "F.Mask" user "Board Geometry/Soldermask Top")
		(3 "B.Mask" user "Board Geometry/Soldermask Bottom")
		(17 "Dwgs.User" user "User.Drawings")
		(19 "Cmts.User" user "User.Comments")
		(21 "Eco1.User" user "User.Eco1")
		(23 "Eco2.User" user "User.Eco2")
		(25 "Edge.Cuts" user "Board Geometry/Outline")
		(27 "Margin" user)
		(31 "F.CrtYd" user "Package Geometry/Place Bound Top")
		(29 "B.CrtYd" user "Package Geometry/Place Bound Bottom")
		(35 "F.Fab" user "Ref Des/Assembly Top")
		(33 "B.Fab" user "Ref Des/Assembly Bottom")
	)
	(footprint ""
		(layer "F.Cu")
		(at 167.386 -23.713948 -90)
		(property "Reference" "R148"
			(at 0 0 270)
			(layer "F.SilkS")
			(hide yes)
			(effects
				(font
					(size 1.27 1.27)
				)
			)
		)
		(property "Value" ""
			(at 0 0 270)
			(layer "F.Fab")
			(effects
				(font
					(size 1.27 1.27)
				)
			)
		)
		(duplicate_pad_numbers_are_jumpers no)
		(fp_line
			(start -0.7874 0.4064)
			(end -0.7874 -0.4064)
			(stroke
				(width 0.1524)
				(type default)
			)
			(layer "F.SilkS")
		)
		(fp_line
			(start 0.7874 0.4064)
			(end -0.7874 0.4064)
			(stroke
				(width 0.1524)
				(type default)
			)
			(layer "F.SilkS")
		)
		(fp_line
			(start -0.7874 -0.4064)
			(end 0.7874 -0.4064)
			(stroke
				(width 0.1524)
				(type default)
			)
			(layer "F.SilkS")
		)
		(fp_line
			(start 0.7874 -0.4064)
			(end 0.7874 0.4064)
			(stroke
				(width 0.1524)
				(type default)
			)
			(layer "F.SilkS")
		)
		(fp_line
			(start -0.67945 0.3048)
			(end -0.67945 -0.305054)
			(stroke
				(width 0.1)
				(type default)
			)
			(layer "F.Fab")
		)
		(fp_line
			(start -0.12065 0.3048)
			(end -0.67945 0.3048)
			(stroke
				(width 0.1)
				(type default)
			)
			(layer "F.Fab")
		)
		(fp_line
			(start 0.120396 0.3048)
			(end 0.120396 0.2794)
			(stroke
				(width 0.1)
				(type default)
			)
			(layer "F.Fab")
		)
		(fp_line
			(start 0.67945 0.3048)
			(end 0.120396 0.3048)
			(stroke
				(width 0.1)
				(type default)
			)
			(layer "F.Fab")
		)
		(fp_line
			(start -0.12065 0.2794)
			(end -0.12065 0.3048)
			(stroke
				(width 0.1)
				(type default)
			)
			(layer "F.Fab")
		)
		(fp_line
			(start 0.120396 0.2794)
			(end -0.12065 0.2794)
			(stroke
				(width 0.1)
				(type default)
			)
			(layer "F.Fab")
		)
		(fp_line
			(start -0.12065 -0.2794)
			(end 0.12065 -0.2794)
			(stroke
				(width 0.1)
				(type default)
			)
			(layer "F.Fab")
		)
		(fp_line
			(start 0.12065 -0.2794)
			(end 0.12065 -0.3048)
			(stroke
				(width 0.1)
				(type default)
			)
			(layer "F.Fab")
		)
		(fp_line
			(start 0.12065 -0.3048)
			(end 0.67945 -0.3048)
			(stroke
				(width 0.1)
				(type default)
			)
			(layer "F.Fab")
		)
		(fp_line
			(start 0.67945 -0.3048)
			(end 0.67945 0.3048)
			(stroke
				(width 0.1)
				(type default)
			)
			(layer "F.Fab")
		)
		(fp_line
			(start -0.67945 -0.305054)
			(end -0.12065 -0.305054)
			(stroke
				(width 0.1)
				(type default)
			)
			(layer "F.Fab")
		)
		(fp_line
			(start -0.12065 -0.305054)
			(end -0.12065 -0.2794)
			(stroke
				(width 0.1)
				(type default)
			)
			(layer "F.Fab")
		)
		(pad "1" smd circle
			(at -0.40005 0 270)
			(size 0 0)
			(layers "F.Cu" "F.Mask" "F.Paste")
			(net "PECI_BMC_R")
		)
		(pad "2" smd circle
			(at 0.40005 0 270)
			(size 0 0)
			(layers "F.Cu" "F.Mask" "F.Paste")
			(net "GND")
		)
	)
	(footprint ""
		(layer "F.Cu")
		(at 427.176438 -181.53507 90)
		(property "Reference" "PC1273"
			(at 0 0 90)
			(layer "F.SilkS")
			(hide yes)
			(effects
				(font
					(size 1.27 1.27)
				)
			)
		)
		(property "Value" ""
			(at 0 0 90)
			(layer "F.Fab")
			(effects
				(font
					(size 1.27 1.27)
				)
			)
		)
		(duplicate_pad_numbers_are_jumpers no)
		(fp_line
			(start 1.524 -0.762)
			(end 1.524 0.762)
			(stroke
				(width 0.1524)
				(type default)
			)
			(layer "F.SilkS")
		)
		(fp_line
			(start -1.524 -0.762)
			(end 1.524 -0.762)
			(stroke
				(width 0.1524)
				(type default)
			)
			(layer "F.SilkS")
		)
		(fp_line
			(start 1.524 0.762)
			(end -1.524 0.762)
			(stroke
				(width 0.1524)
				(type default)
			)
			(layer "F.SilkS")
		)
		(fp_line
			(start -1.524 0.762)
			(end -1.524 -0.762)
			(stroke
				(width 0.1524)
				(type default)
			)
			(layer "F.SilkS")
		)
		(fp_line
			(start 1.1049 -0.724916)
			(end -1.1049 -0.724916)
			(stroke
				(width 0.1)
				(type default)
			)
			(layer "F.Fab")
		)
		(fp_line
			(start -1.1049 -0.724916)
			(end -1.1049 0.724916)
			(stroke
				(width 0.1)
				(type default)
			)
			(layer "F.Fab")
		)
		(fp_line
			(start 1.1049 0.724916)
			(end 1.1049 -0.724916)
			(stroke
				(width 0.1)
				(type default)
			)
			(layer "F.Fab")
		)
		(fp_line
			(start -1.1049 0.724916)
			(end 1.1049 0.724916)
			(stroke
				(width 0.1)
				(type default)
			)
			(layer "F.Fab")
		)
		(pad "1" smd rect
			(at -0.889 0 270)
			(size 1.016 1.27)
			(layers "F.Cu" "F.Mask" "F.Paste")
			(net "SW_P12V_PVCCINFAON_CPU0_FLT")
		)
		(pad "2" smd rect
			(at 0.889 0 270)
			(size 1.016 1.27)
			(layers "F.Cu" "F.Mask" "F.Paste")
			(net "GND")
		)
	)
)
